FILE_TYPE=LIBRARY_PARTS;
primitive 'PI3EQX1002EZREX';
  pin
    'GND_2':
      PIN_NUMBER='(9)';
      PINUSE='POWER';
      NO_LOAD_CHECK='Both';
      NO_IO_CHECK='Both';
      NO_ASSERT_CHECK='TRUE';
      NO_DIR_CHECK='TRUE';
      ALLOW_CONNECT='TRUE';
    'VDD_2':
      PIN_NUMBER='(17)';
      PINUSE='POWER';
      NO_LOAD_CHECK='Both';
      NO_IO_CHECK='Both';
      NO_ASSERT_CHECK='TRUE';
      NO_DIR_CHECK='TRUE';
      ALLOW_CONNECT='TRUE';
    'EN':
      PIN_NUMBER='(4)';
      INPUT_LOAD='(-0.01,0.01)';
    'VDD_1':
      PIN_NUMBER='(5)';
      PINUSE='POWER';
      NO_LOAD_CHECK='Both';
      NO_IO_CHECK='Both';
      NO_ASSERT_CHECK='TRUE';
      NO_DIR_CHECK='TRUE';
      ALLOW_CONNECT='TRUE';
    'AON':
      PIN_NUMBER='(23)';
      OUTPUT_LOAD='(1.0,-1.0)';
    'AOP':
      PIN_NUMBER='(24)';
      OUTPUT_LOAD='(1.0,-1.0)';
    'GND_6':
      PIN_NUMBER='(22)';
      PINUSE='POWER';
      NO_LOAD_CHECK='Both';
      NO_IO_CHECK='Both';
      NO_ASSERT_CHECK='TRUE';
      NO_DIR_CHECK='TRUE';
      ALLOW_CONNECT='TRUE';
    'AIN':
      PIN_NUMBER='(7)';
      INPUT_LOAD='(-0.01,0.01)';
    'EQA':
      PIN_NUMBER='(1)';
      INPUT_LOAD='(-0.01,0.01)';
    'FGA':
      PIN_NUMBER='(2)';
      INPUT_LOAD='(-0.01,0.01)';
    'RXDET_EN':
      PIN_NUMBER='(13)';
      INPUT_LOAD='(-0.01,0.01)';
    'AIP':
      PIN_NUMBER='(6)';
      INPUT_LOAD='(-0.01,0.01)';
    'TH_GND':
      PIN_NUMBER='(TH)';
      PINUSE='POWER';
      NO_LOAD_CHECK='Both';
      NO_IO_CHECK='Both';
      NO_ASSERT_CHECK='TRUE';
      NO_DIR_CHECK='TRUE';
      ALLOW_CONNECT='TRUE';
    'FGB':
      PIN_NUMBER='(15)';
      INPUT_LOAD='(-0.01,0.01)';
    'BIN':
      PIN_NUMBER='(19)';
      INPUT_LOAD='(-0.01,0.01)';
    'SWB':
      PIN_NUMBER='(14)';
      INPUT_LOAD='(-0.01,0.01)';
    'BIP':
      PIN_NUMBER='(18)';
      INPUT_LOAD='(-0.01,0.01)';
    'SWA':
      PIN_NUMBER='(3)';
      INPUT_LOAD='(-0.01,0.01)';
    'GND_1':
      PIN_NUMBER='(8)';
      PINUSE='POWER';
      NO_LOAD_CHECK='Both';
      NO_IO_CHECK='Both';
      NO_ASSERT_CHECK='TRUE';
      NO_DIR_CHECK='TRUE';
      ALLOW_CONNECT='TRUE';
    'EQB':
      PIN_NUMBER='(16)';
      INPUT_LOAD='(-0.01,0.01)';
    'GND_3':
      PIN_NUMBER='(10)';
      PINUSE='POWER';
      NO_LOAD_CHECK='Both';
      NO_IO_CHECK='Both';
      NO_ASSERT_CHECK='TRUE';
      NO_DIR_CHECK='TRUE';
      ALLOW_CONNECT='TRUE';
    'GND_5':
      PIN_NUMBER='(21)';
      PINUSE='POWER';
      NO_LOAD_CHECK='Both';
      NO_IO_CHECK='Both';
      NO_ASSERT_CHECK='TRUE';
      NO_DIR_CHECK='TRUE';
      ALLOW_CONNECT='TRUE';
    'BON':
      PIN_NUMBER='(11)';
      OUTPUT_LOAD='(1.0,-1.0)';
    'BOP':
      PIN_NUMBER='(12)';
      OUTPUT_LOAD='(1.0,-1.0)';
    'GND_4':
      PIN_NUMBER='(20)';
      PINUSE='POWER';
      NO_LOAD_CHECK='Both';
      NO_IO_CHECK='Both';
      NO_ASSERT_CHECK='TRUE';
      NO_DIR_CHECK='TRUE';
      ALLOW_CONNECT='TRUE';
  end_pin;
  body
    PART_NAME='PI3EQX1002EZREX';
    BODY_NAME='PI3EQX1002EZREX';
    PHYS_DES_PREFIX='U';
    CLASS='IC';
  end_body;
end_primitive;

END.
